(kicad_pcb
	(version 20260206)
	(generator "pcbnew")
	(generator_version "10.0")
	(general
		(thickness 1.6)
		(legacy_teardrops no)
	)
	(paper "A4")
	(title_block
		(title "v1-chassis-manager — T6M_CM_d_v01_1031_1645.brd")
		(comment 1 "Open CloudServer (Microsoft) / footprints 1201-1207 of 2512")
	)
	(layers
		(0 "F.Cu" signal "TOP")
		(4 "In1.Cu" signal "GND1")
		(6 "In2.Cu" signal "IN1")
		(8 "In3.Cu" signal "VCC1")
		(10 "In4.Cu" signal "VCC2")
		(12 "In5.Cu" signal "GND2")
		(14 "In6.Cu" signal "IN2")
		(16 "In7.Cu" signal "IN3")
		(18 "In8.Cu" signal "GND3")
		(2 "B.Cu" signal "BOTTOM")
		(9 "F.Adhes" user "F.Adhesive")
		(11 "B.Adhes" user "B.Adhesive")
		(13 "F.Paste" user "Package Geometry/Pastemask Top")
		(15 "B.Paste" user "Package Geometry/Pastemask Bottom")
		(5 "F.SilkS" user "Ref Des/Silkscreen Top")
		(7 "B.SilkS" user "Ref Des/Silkscreen Bottom")
		(1 "F.Mask" user "Board Geometry/Soldermask Top")
		(3 "B.Mask" user "Board Geometry/Soldermask Bottom")
		(17 "Dwgs.User" user "User.Drawings")
		(19 "Cmts.User" user "User.Comments")
		(21 "Eco1.User" user "User.Eco1")
		(23 "Eco2.User" user "User.Eco2")
		(25 "Edge.Cuts" user "Board Geometry/Outline")
		(27 "Margin" user)
		(31 "F.CrtYd" user "Package Geometry/Place Bound Top")
		(29 "B.CrtYd" user "Package Geometry/Place Bound Bottom")
		(35 "F.Fab" user "Ref Des/Assembly Top")
		(33 "B.Fab" user "Ref Des/Assembly Bottom")
	)
	(footprint ""
		(layer "F.Cu")
		(at 102.393496 -141.891004 90)
		(property "Reference" "PJ17"
			(at 4.273296 -0.777494 0)
			(unlocked yes)
			(layer "F.SilkS")
			(effects
				(font
					(size 0.635 0.4064)
					(thickness 0.1524)
				)
				(justify left)
			)
		)
		(property "Value" ""
			(at 0 0 90)
			(layer "F.Fab")
			(effects
				(font
					(size 1.27 1.27)
				)
			)
		)
		(duplicate_pad_numbers_are_jumpers no)
		(fp_poly
			(pts
				(xy -0.360426 0.359156) (xy -0.360426 -0.381) (xy 0.3556 -0.381) (xy 0.3556 1.905) (xy -0.360426 1.905)
			)
			(stroke
				(width 0)
				(type default)
			)
			(fill no)
			(layer "F.CrtYd")
		)
		(pad "1" smd custom
			(at 0 0 90)
			(size 0.1778 0.1778)
			(layers "F.Cu" "F.Mask" "F.Paste")
			(net "GND")
			(options
				(clearance outline)
				(anchor circle)
			)
			(primitives
				(gr_poly
					(pts
						(xy -0.127 0.9398) (xy -0.127 -0.127) (xy -0.3556 -0.127) (xy -0.3556 -0.9398) (xy 0.3556 -0.9398)
						(xy 0.3556 -0.127) (xy 0.127 -0.127) (xy 0.127 0.9398)
					)
					(width 0)
					(fill yes)
				)
			)
		)
		(pad "2" smd rect
			(at 0 1.4986 270)
			(size 0.7112 0.8128)
			(layers "F.Cu" "F.Mask" "F.Paste")
			(net "AGND_PVCCP_NODE1")
		)
		(zone
			(layer "F.Cu")
			(hatch none 0.5)
			(connect_pads
				(clearance 0)
			)
			(min_thickness 0.25)
			(keepout
				(tracks allowed)
				(vias not_allowed)
				(pads allowed)
				(copperpour not_allowed)
				(footprints allowed)
			)
			(placement
				(enabled no)
				(sheetname "")
			)
			(fill
				(thermal_gap 0.5)
				(thermal_bridge_width 0.5)
				(island_removal_mode 0)
			)
			(polygon
				(pts
					(xy 104.349296 -142.297404) (xy 101.961696 -142.297404) (xy 101.961696 -141.479778) (xy 104.349296 -141.479778)
				)
			)
		)
	)
	(footprint ""
		(layer "F.Cu")
		(at 191.4525 -26.714704 180)
		(property "Reference" "C556"
			(at 1.275842 -2.018538 0)
			(unlocked yes)
			(layer "F.SilkS")
			(effects
				(font
					(size 0.7874 0.5842)
					(thickness 0.1524)
				)
				(justify left)
			)
		)
		(property "Value" ""
			(at 0 0 180)
			(layer "F.Fab")
			(effects
				(font
					(size 1.27 1.27)
				)
			)
		)
		(duplicate_pad_numbers_are_jumpers no)
		(fp_line
			(start 1.905 0.8636)
			(end -1.905 0.8636)
			(stroke
				(width 0.1524)
				(type default)
			)
			(layer "F.SilkS")
		)
		(fp_line
			(start 1.905 -0.8636)
			(end 1.905 0.8636)
			(stroke
				(width 0.1524)
				(type default)
			)
			(layer "F.SilkS")
		)
		(fp_line
			(start 0 0.8382)
			(end 0 -0.8382)
			(stroke
				(width 0.1524)
				(type default)
			)
			(layer "F.SilkS")
		)
		(fp_line
			(start -1.905 0.8636)
			(end -1.905 -0.8636)
			(stroke
				(width 0.1524)
				(type default)
			)
			(layer "F.SilkS")
		)
		(fp_line
			(start -1.905 -0.8636)
			(end 1.905 -0.8636)
			(stroke
				(width 0.1524)
				(type default)
			)
			(layer "F.SilkS")
		)
		(fp_rect
			(start -1.524 0.7366)
			(end 1.524 -0.7366)
			(stroke
				(width 0)
				(type default)
			)
			(fill no)
			(layer "F.CrtYd")
		)
		(pad "1" smd rect
			(at 0.94996 0 180)
			(size 1.1176 1.3716)
			(layers "F.Cu" "F.Mask" "F.Paste")
			(net "P5V_NODE1")
		)
		(pad "2" smd rect
			(at -0.94996 0 180)
			(size 1.1176 1.3716)
			(layers "F.Cu" "F.Mask" "F.Paste")
			(net "GND")
		)
	)
	(footprint ""
		(layer "F.Cu")
		(at 119.48922 -185.209942 -90)
		(property "Reference" "C635"
			(at -4.774692 -0.35306 90)
			(unlocked yes)
			(layer "F.SilkS")
			(effects
				(font
					(size 0.7874 0.5842)
					(thickness 0.1524)
				)
				(justify left)
			)
		)
		(property "Value" ""
			(at 0 0 270)
			(layer "F.Fab")
			(effects
				(font
					(size 1.27 1.27)
				)
			)
		)
		(duplicate_pad_numbers_are_jumpers no)
		(fp_line
			(start -0.7874 0.4064)
			(end -0.7874 -0.4064)
			(stroke
				(width 0.1524)
				(type default)
			)
			(layer "F.SilkS")
		)
		(fp_line
			(start 0.7874 0.4064)
			(end -0.7874 0.4064)
			(stroke
				(width 0.1524)
				(type default)
			)
			(layer "F.SilkS")
		)
		(fp_line
			(start 0 0.381)
			(end 0 -0.381)
			(stroke
				(width 0.1524)
				(type default)
			)
			(layer "F.SilkS")
		)
		(fp_line
			(start -0.7874 -0.4064)
			(end 0.7874 -0.4064)
			(stroke
				(width 0.1524)
				(type default)
			)
			(layer "F.SilkS")
		)
		(fp_line
			(start 0.7874 -0.4064)
			(end 0.7874 0.4064)
			(stroke
				(width 0.1524)
				(type default)
			)
			(layer "F.SilkS")
		)
		(fp_poly
			(pts
				(xy -0.5334 0.254) (xy -0.635 0.254) (xy -0.635 0.2286) (xy -0.635 -0.254) (xy -0.5334 -0.254) (xy -0.5334 -0.2794)
				(xy 0.5334 -0.2794) (xy 0.5334 -0.254) (xy 0.635 -0.254) (xy 0.635 0.254) (xy 0.5334 0.254) (xy 0.5334 0.2794)
				(xy -0.508 0.2794) (xy -0.5334 0.2794)
			)
			(stroke
				(width 0)
				(type default)
			)
			(fill no)
			(layer "F.CrtYd")
		)
		(pad "1" smd rect
			(at 0.40005 0 270)
			(size 0.4572 0.508)
			(layers "F.Cu" "F.Mask" "F.Paste")
			(net "T7_NODE1_EN_R")
		)
		(pad "2" smd rect
			(at -0.40005 0 270)
			(size 0.4572 0.508)
			(layers "F.Cu" "F.Mask" "F.Paste")
			(net "GND")
		)
	)
	(footprint ""
		(layer "F.Cu")
		(at 147.11045 -51.671474 -90)
		(property "Reference" "R630"
			(at -16.205708 -28.023566 90)
			(unlocked yes)
			(layer "F.SilkS")
			(effects
				(font
					(size 0.7874 0.5842)
					(thickness 0.1524)
				)
				(justify left)
			)
		)
		(property "Value" ""
			(at 0 0 270)
			(layer "F.Fab")
			(effects
				(font
					(size 1.27 1.27)
				)
			)
		)
		(duplicate_pad_numbers_are_jumpers no)
		(fp_line
			(start -1.905 0.8636)
			(end -1.905 -0.8636)
			(stroke
				(width 0.1524)
				(type default)
			)
			(layer "F.SilkS")
		)
		(fp_line
			(start 1.905 0.8636)
			(end -1.905 0.8636)
			(stroke
				(width 0.1524)
				(type default)
			)
			(layer "F.SilkS")
		)
		(fp_line
			(start -1.905 -0.8636)
			(end 1.905 -0.8636)
			(stroke
				(width 0.1524)
				(type default)
			)
			(layer "F.SilkS")
		)
		(fp_line
			(start 1.905 -0.8636)
			(end 1.905 0.8636)
			(stroke
				(width 0.1524)
				(type default)
			)
			(layer "F.SilkS")
		)
		(fp_poly
			(pts
				(xy 1.524 0.6858) (xy 1.524 -0.6858) (xy 1.524 -0.7366) (xy -1.524 -0.7366) (xy -1.524 -0.6858)
				(xy -1.524 0.6858) (xy -1.524 0.7366) (xy 1.524 0.7366)
			)
			(stroke
				(width 0)
				(type default)
			)
			(fill no)
			(layer "F.CrtYd")
		)
		(pad "1" smd rect
			(at 0.94996 0 270)
			(size 1.1176 1.3716)
			(layers "F.Cu" "F.Mask" "F.Paste")
			(net "GND")
		)
		(pad "2" smd rect
			(at -0.94996 0 270)
			(size 1.1176 1.3716)
			(layers "F.Cu" "F.Mask" "F.Paste")
			(net "SATA_P7")
		)
	)
	(footprint ""
		(layer "F.Cu")
		(at 162.696906 -117.319552)
		(property "Reference" "R176"
			(at -4.621784 0.897636 0)
			(unlocked yes)
			(layer "F.SilkS")
			(effects
				(font
					(size 0.7874 0.5842)
					(thickness 0.1524)
				)
				(justify left)
			)
		)
		(property "Value" ""
			(at 0 0 0)
			(layer "F.Fab")
			(effects
				(font
					(size 1.27 1.27)
				)
			)
		)
		(duplicate_pad_numbers_are_jumpers no)
		(fp_line
			(start -0.7874 -0.4064)
			(end 0.7874 -0.4064)
			(stroke
				(width 0.1524)
				(type default)
			)
			(layer "F.SilkS")
		)
		(fp_line
			(start -0.7874 0.4064)
			(end -0.7874 -0.4064)
			(stroke
				(width 0.1524)
				(type default)
			)
			(layer "F.SilkS")
		)
		(fp_line
			(start 0.7874 -0.4064)
			(end 0.7874 0.4064)
			(stroke
				(width 0.1524)
				(type default)
			)
			(layer "F.SilkS")
		)
		(fp_line
			(start 0.7874 0.4064)
			(end -0.7874 0.4064)
			(stroke
				(width 0.1524)
				(type default)
			)
			(layer "F.SilkS")
		)
		(fp_poly
			(pts
				(xy -0.508 0.2794) (xy -0.508 0.2286) (xy -0.635 0.2286) (xy -0.635 -0.254) (xy -0.5334 -0.254)
				(xy -0.5334 -0.2794) (xy 0.5334 -0.2794) (xy 0.5334 -0.254) (xy 0.635 -0.254) (xy 0.635 0.254) (xy 0.5334 0.254)
				(xy 0.5334 0.2794)
			)
			(stroke
				(width 0)
				(type default)
			)
			(fill no)
			(layer "F.CrtYd")
		)
		(pad "1" smd rect
			(at 0.40005 0)
			(size 0.4572 0.508)
			(layers "F.Cu" "F.Mask" "F.Paste")
			(net "RST_CPU_NODE1_SRTCRST_L")
		)
		(pad "2" smd rect
			(at -0.40005 0)
			(size 0.4572 0.508)
			(layers "F.Cu" "F.Mask" "F.Paste")
			(net "GND")
		)
	)
	(footprint ""
		(layer "F.Cu")
		(at 46.121828 -4.35483 90)
		(property "Reference" "PC73"
			(at -3.775202 -14.21384 90)
			(unlocked yes)
			(layer "F.SilkS")
			(effects
				(font
					(size 0.7874 0.5842)
					(thickness 0.1524)
				)
				(justify left)
			)
		)
		(property "Value" ""
			(at 0 0 90)
			(layer "F.Fab")
			(effects
				(font
					(size 1.27 1.27)
				)
			)
		)
		(duplicate_pad_numbers_are_jumpers no)
		(fp_line
			(start 2.2098 -0.9398)
			(end 2.2098 0.9398)
			(stroke
				(width 0.1524)
				(type default)
			)
			(layer "F.SilkS")
		)
		(fp_line
			(start 0 -0.9398)
			(end 0 0.9398)
			(stroke
				(width 0.1524)
				(type default)
			)
			(layer "F.SilkS")
		)
		(fp_line
			(start -2.2098 -0.9398)
			(end 2.2098 -0.9398)
			(stroke
				(width 0.1524)
				(type default)
			)
			(layer "F.SilkS")
		)
		(fp_line
			(start 2.2098 0.9398)
			(end -2.2098 0.9398)
			(stroke
				(width 0.1524)
				(type default)
			)
			(layer "F.SilkS")
		)
		(fp_line
			(start -2.2098 0.9398)
			(end -2.2098 -0.9398)
			(stroke
				(width 0.1524)
				(type default)
			)
			(layer "F.SilkS")
		)
		(fp_poly
			(pts
				(xy -1.6764 0.889) (xy -1.6764 0.7874) (xy -2.0574 0.7874) (xy -2.0574 -0.7874) (xy -1.6764 -0.7874)
				(xy -1.6764 -0.9398) (xy 1.6764 -0.9398) (xy 1.6764 -0.7874) (xy 2.0574 -0.7874) (xy 2.0574 0.7874)
				(xy 1.6764 0.7874) (xy 1.6764 0.9398) (xy -1.6764 0.9398)
			)
			(stroke
				(width 0)
				(type default)
			)
			(fill no)
			(layer "F.CrtYd")
		)
		(fp_line
			(start 1.700022 -0.899922)
			(end 1.700022 0.899922)
			(stroke
				(width 0.1)
				(type default)
			)
			(layer "F.Fab")
		)
		(fp_line
			(start -1.700022 -0.899922)
			(end 1.700022 -0.899922)
			(stroke
				(width 0.1)
				(type default)
			)
			(layer "F.Fab")
		)
		(fp_line
			(start 1.700022 0.899922)
			(end -1.700022 0.899922)
			(stroke
				(width 0.1)
				(type default)
			)
			(layer "F.Fab")
		)
		(fp_line
			(start -1.700022 0.899922)
			(end -1.700022 -0.899922)
			(stroke
				(width 0.1)
				(type default)
			)
			(layer "F.Fab")
		)
		(pad "1" smd rect
			(at 1.4732 0 90)
			(size 1.1684 1.5748)
			(layers "F.Cu" "F.Mask" "F.Paste")
			(net "SW_PV_VDDR_NODE1_VIN_FLT")
		)
		(pad "2" smd rect
			(at -1.4732 0 90)
			(size 1.1684 1.5748)
			(layers "F.Cu" "F.Mask" "F.Paste")
			(net "GND")
		)
	)
	(footprint ""
		(layer "F.Cu")
		(at 7.465568 -145.471642 180)
		(property "Reference" "U56"
			(at 5.543296 -1.264666 90)
			(unlocked yes)
			(layer "F.SilkS")
			(effects
				(font
					(size 0.7874 0.5842)
					(thickness 0.1524)
				)
				(justify left)
			)
		)
		(property "Value" ""
			(at 0 0 180)
			(layer "F.Fab")
			(effects
				(font
					(size 1.27 1.27)
				)
			)
		)
		(duplicate_pad_numbers_are_jumpers no)
		(fp_line
			(start 4.9022 2.0066)
			(end -4.9022 2.0066)
			(stroke
				(width 0.1524)
				(type default)
			)
			(layer "F.SilkS")
		)
		(fp_line
			(start 4.9022 -2.0066)
			(end 4.9022 2.0066)
			(stroke
				(width 0.1524)
				(type default)
			)
			(layer "F.SilkS")
		)
		(fp_line
			(start -4.318 0)
			(end -4.9022 -0.5842)
			(stroke
				(width 0.1524)
				(type default)
			)
			(layer "F.SilkS")
		)
		(fp_line
			(start -4.9022 2.0066)
			(end -4.9022 0.5842)
			(stroke
				(width 0.1524)
				(type default)
			)
			(layer "F.SilkS")
		)
		(fp_line
			(start -4.9022 0.5842)
			(end -4.318 0)
			(stroke
				(width 0.1524)
				(type default)
			)
			(layer "F.SilkS")
		)
		(fp_line
			(start -4.9022 -0.5842)
			(end -4.9022 -2.0066)
			(stroke
				(width 0.1524)
				(type default)
			)
			(layer "F.SilkS")
		)
		(fp_line
			(start -4.9022 -2.0066)
			(end 4.9022 -2.0066)
			(stroke
				(width 0.1524)
				(type default)
			)
			(layer "F.SilkS")
		)
		(fp_circle
			(center -4.318 1.524)
			(end -4.572 1.524)
			(stroke
				(width 0.1524)
				(type default)
			)
			(fill no)
			(layer "F.SilkS")
		)
		(fp_rect
			(start -4.9022 3.6703)
			(end 4.9022 -3.6703)
			(stroke
				(width 0)
				(type default)
			)
			(fill no)
			(layer "F.CrtYd")
		)
		(pad "1" smd rect
			(at -4.225036 2.921 180)
			(size 0.3556 1.4986)
			(layers "F.Cu" "F.Mask" "F.Paste")
			(net "N54310596")
		)
		(pad "2" smd rect
			(at -3.57505 2.921 180)
			(size 0.3556 1.4986)
			(layers "F.Cu" "F.Mask" "F.Paste")
			(net "N54310598")
		)
		(pad "3" smd rect
			(at -2.925064 2.921 180)
			(size 0.3556 1.4986)
			(layers "F.Cu" "F.Mask" "F.Paste")
			(net "N54310606")
		)
		(pad "4" smd rect
			(at -2.275078 2.921 180)
			(size 0.3556 1.4986)
			(layers "F.Cu" "F.Mask" "F.Paste")
			(net "UART_RX_P6_L")
		)
		(pad "5" smd rect
			(at -1.625092 2.921 180)
			(size 0.3556 1.4986)
			(layers "F.Cu" "F.Mask" "F.Paste")
			(net "UART_RI_P6_L_N")
		)
		(pad "6" smd rect
			(at -0.975106 2.921 180)
			(size 0.3556 1.4986)
			(layers "F.Cu" "F.Mask" "F.Paste")
			(net "UART_DSR_P6_L_N")
		)
		(pad "7" smd rect
			(at -0.32512 2.921 180)
			(size 0.3556 1.4986)
			(layers "F.Cu" "F.Mask" "F.Paste")
			(net "UART_CTS_P6_L_N")
		)
		(pad "8" smd rect
			(at 0.32512 2.921 180)
			(size 0.3556 1.4986)
			(layers "F.Cu" "F.Mask" "F.Paste")
			(net "N54310531")
		)
		(pad "9" smd rect
			(at 0.975106 2.921 180)
			(size 0.3556 1.4986)
			(layers "F.Cu" "F.Mask" "F.Paste")
			(net "UART_RTS_P6_L_N")
		)
		(pad "10" smd rect
			(at 1.625092 2.921 180)
			(size 0.3556 1.4986)
			(layers "F.Cu" "F.Mask" "F.Paste")
			(net "UART_TX_P6_L")
		)
		(pad "11" smd rect
			(at 2.275078 2.921 180)
			(size 0.3556 1.4986)
			(layers "F.Cu" "F.Mask" "F.Paste")
			(net "UART_DTR_P6_L_N")
		)
		(pad "12" smd rect
			(at 2.925064 2.921 180)
			(size 0.3556 1.4986)
			(layers "F.Cu" "F.Mask" "F.Paste")
			(net "UART_DTR_P6_N")
		)
		(pad "13" smd rect
			(at 3.57505 2.921 180)
			(size 0.3556 1.4986)
			(layers "F.Cu" "F.Mask" "F.Paste")
			(net "UART_TX_P6")
		)
		(pad "14" smd rect
			(at 4.225036 2.921 180)
			(size 0.3556 1.4986)
			(layers "F.Cu" "F.Mask" "F.Paste")
			(net "UART_RTS_P6_N")
		)
		(pad "15" smd rect
			(at 4.225036 -2.921 180)
			(size 0.3556 1.4986)
			(layers "F.Cu" "F.Mask" "F.Paste")
			(net "Net_2303")
		)
		(pad "16" smd rect
			(at 3.57505 -2.921 180)
			(size 0.3556 1.4986)
			(layers "F.Cu" "F.Mask" "F.Paste")
			(net "UART_CTS_P6_N")
		)
		(pad "17" smd rect
			(at 2.925064 -2.921 180)
			(size 0.3556 1.4986)
			(layers "F.Cu" "F.Mask" "F.Paste")
			(net "UART_DSR_P6_N")
		)
		(pad "18" smd rect
			(at 2.275078 -2.921 180)
			(size 0.3556 1.4986)
			(layers "F.Cu" "F.Mask" "F.Paste")
			(net "UART_RI_P6_LS_N")
		)
		(pad "19" smd rect
			(at 1.625092 -2.921 180)
			(size 0.3556 1.4986)
			(layers "F.Cu" "F.Mask" "F.Paste")
			(net "UART_RX_P6")
		)
		(pad "20" smd rect
			(at 0.975106 -2.921 180)
			(size 0.3556 1.4986)
			(layers "F.Cu" "F.Mask" "F.Paste")
			(net "Net_2304")
		)
		(pad "21" smd rect
			(at 0.32512 -2.921 180)
			(size 0.3556 1.4986)
			(layers "F.Cu" "F.Mask" "F.Paste")
			(net "Net_2305")
		)
		(pad "22" smd rect
			(at -0.32512 -2.921 180)
			(size 0.3556 1.4986)
			(layers "F.Cu" "F.Mask" "F.Paste")
			(net "N54310545")
		)
		(pad "23" smd rect
			(at -0.975106 -2.921 180)
			(size 0.3556 1.4986)
			(layers "F.Cu" "F.Mask" "F.Paste")
			(net "N54310543")
		)
		(pad "24" smd rect
			(at -1.625092 -2.921 180)
			(size 0.3556 1.4986)
			(layers "F.Cu" "F.Mask" "F.Paste")
			(net "N54310592")
		)
		(pad "25" smd rect
			(at -2.275078 -2.921 180)
			(size 0.3556 1.4986)
			(layers "F.Cu" "F.Mask" "F.Paste")
			(net "GND")
		)
		(pad "26" smd rect
			(at -2.925064 -2.921 180)
			(size 0.3556 1.4986)
			(layers "F.Cu" "F.Mask" "F.Paste")
			(net "P3V3_NODE1")
		)
		(pad "27" smd rect
			(at -3.57505 -2.921 180)
			(size 0.3556 1.4986)
			(layers "F.Cu" "F.Mask" "F.Paste")
			(net "N54310604")
		)
		(pad "28" smd rect
			(at -4.225036 -2.921 180)
			(size 0.3556 1.4986)
			(layers "F.Cu" "F.Mask" "F.Paste")
			(net "N54310590")
		)
	)
)
